#ISCELL
  logical_power cad_note *
  *
#ISCELL
  mstr_misc dns *
  *
#ISCELL
  pure_quanta quanta_title_block_c *
  *
#ISCELL
  logical_power universal_gnd *
  page239_i101
#ISCELL
  logical_power universal_gnd *
  page239_i102
#CELL
  pure_quanta adc128d818cimtxnopb *
  page239_i103
#ISCELL
  standard offpage *
  page239_i108
#ISCELL
  standard offpage *
  page239_i109
#CELL
  pure_quanta q_res *
  page239_i110
#CELL
  pure_quanta q_res *
  page239_i111
#ISCELL
  standard offpage *
  page239_i112
#ISCELL
  standard offpage *
  page239_i113
#ISCELL
  standard offpage *
  page239_i114
#ISCELL
  standard offpage *
  page239_i115
#ISCELL
  logical_power universal_power *
  page239_i117
#CELL
  pure_quanta q_inductor *
  page239_i118
#ISCELL
  standard offpage *
  page239_i125
#ISCELL
  standard offpage *
  page239_i126
#CELL
  pure_quanta q_cap *
  page239_i127
#CELL
  pure_quanta q_cap *
  page239_i128
#CELL
  pure_quanta q_res *
  page239_i129
#ISCELL
  logical_power universal_gnd *
  page239_i130
#CELL
  pure_quanta q_res *
  page239_i131
#ISCELL
  logical_power universal_gnd *
  page239_i132
#ISCELL
  logical_power universal_gnd *
  page239_i133
#ISCELL
  logical_power universal_power *
  page239_i140
#CELL
  pure_quanta q_res *
  page239_i141
#CELL
  pure_quanta q_res *
  page239_i149
#ISCELL
  logical_power universal_gnd *
  page239_i150
#ISCELL
  logical_power universal_power *
  page239_i160
#CELL
  pure_quanta q_res *
  page239_i161
#CELL
  pure_quanta q_res *
  page239_i162
#CELL
  pure_quanta q_res *
  page239_i163
#ISCELL
  logical_power universal_power *
  page239_i167
#CELL
  pure_quanta q_res *
  page239_i168
#ISCELL
  logical_power universal_power *
  page239_i172
#CELL
  pure_quanta q_res *
  page239_i173
#CELL
  pure_quanta q_res *
  page239_i174
#CELL
  pure_quanta q_res *
  page239_i176
#ISCELL
  standard offpage *
  page239_i177
#ISCELL
  standard offpage *
  page239_i178
#CELL
  pure_quanta q_res *
  page239_i179
#CELL
  pure_quanta q_cap *
  page239_i180
#CELL
  pure_quanta q_cap *
  page239_i181
#ISCELL
  logical_power universal_gnd *
  page239_i182
#ISCELL
  logical_power universal_gnd *
  page239_i183
#ISCELL
  standard offpage *
  page239_i184
#ISCELL
  standard offpage *
  page239_i185
#ISCELL
  logical_power universal_gnd *
  page239_i186
#CELL
  pure_quanta q_cap *
  page239_i187
#CELL
  pure_quanta q_cap *
  page239_i188
#ISCELL
  logical_power universal_gnd *
  page239_i189
#CELL
  pure_quanta q_res *
  page239_i19
#CELL
  pure_quanta q_res *
  page239_i190
#CELL
  pure_quanta q_res *
  page239_i191
#ISCELL
  logical_power universal_gnd *
  page239_i192
#ISCELL
  standard offpage *
  page239_i193
#ISCELL
  standard offpage *
  page239_i194
#ISCELL
  logical_power universal_gnd *
  page239_i195
#CELL
  pure_quanta q_cap *
  page239_i196
#CELL
  pure_quanta q_cap *
  page239_i197
#ISCELL
  logical_power universal_gnd *
  page239_i198
#CELL
  pure_quanta q_res *
  page239_i199
#CELL
  pure_quanta q_res *
  page239_i20
#CELL
  pure_quanta q_res *
  page239_i200
#ISCELL
  logical_power universal_gnd *
  page239_i201
#ISCELL
  logical_power universal_gnd *
  page239_i202
#ISCELL
  standard offpage *
  page239_i203
#ISCELL
  standard offpage *
  page239_i204
#CELL
  pure_quanta q_cap *
  page239_i205
#ISCELL
  logical_power universal_gnd *
  page239_i206
#CELL
  pure_quanta q_cap *
  page239_i207
#ISCELL
  logical_power universal_gnd *
  page239_i208
#CELL
  pure_quanta q_res *
  page239_i209
#ISCELL
  standard offpage *
  page239_i21
#CELL
  pure_quanta q_res *
  page239_i210
#ISCELL
  standard offpage *
  page239_i214
#ISCELL
  standard offpage *
  page239_i218
#ISCELL
  standard offpage *
  page239_i22
#ISCELL
  logical_power universal_gnd *
  page239_i222
#CELL
  pure_quanta q_res *
  page239_i223
#CELL
  pure_quanta q_res *
  page239_i224
#ISCELL
  logical_power universal_power *
  page239_i225
#ISCELL
  logical_power universal_gnd *
  page239_i226
#CELL
  pure_quanta q_res *
  page239_i227
#CELL
  pure_quanta q_res *
  page239_i228
#ISCELL
  standard offpage *
  page239_i229
#ISCELL
  standard offpage *
  page239_i23
#ISCELL
  standard offpage *
  page239_i230
#ISCELL
  standard offpage *
  page239_i231
#ISCELL
  standard offpage *
  page239_i232
#ISCELL
  standard offpage *
  page239_i233
#ISCELL
  standard offpage *
  page239_i234
#ISCELL
  standard offpage *
  page239_i235
#CELL
  pure_quanta q_cap *
  page239_i236
#ISCELL
  logical_power universal_gnd *
  page239_i237
#CELL
  pure_quanta q_cap *
  page239_i238
#ISCELL
  logical_power universal_gnd *
  page239_i239
#ISCELL
  standard offpage *
  page239_i24
#CELL
  pure_quanta q_res *
  page239_i240
#CELL
  pure_quanta q_res *
  page239_i241
#ISCELL
  standard offpage *
  page239_i288
#ISCELL
  standard offpage *
  page239_i289
#ISCELL
  standard offpage *
  page239_i290
#ISCELL
  standard offpage *
  page239_i291
#ISCELL
  standard offpage *
  page239_i292
#ISCELL
  standard offpage *
  page239_i293
#ISCELL
  standard offpage *
  page239_i294
#ISCELL
  standard offpage *
  page239_i295
#ISCELL
  standard offpage *
  page239_i297
#ISCELL
  standard offpage *
  page239_i298
#ISCELL
  standard offpage *
  page239_i299
#ISCELL
  standard offpage *
  page239_i300
#ISCELL
  standard offpage *
  page239_i301
#ISCELL
  standard offpage *
  page239_i302
#ISCELL
  logical_power universal_gnd *
  page239_i303
#CELL
  pure_quanta q_cap *
  page239_i304
#CELL
  pure_quanta q_cap *
  page239_i305
#ISCELL
  logical_power universal_gnd *
  page239_i306
#ISCELL
  standard offpage *
  page239_i307
#ISCELL
  standard offpage *
  page239_i308
#CELL
  pure_quanta q_cap *
  page239_i309
#ISCELL
  logical_power universal_gnd *
  page239_i310
#CELL
  pure_quanta q_cap *
  page239_i311
#ISCELL
  logical_power universal_gnd *
  page239_i312
#CELL
  pure_quanta q_res *
  page239_i313
#CELL
  pure_quanta q_res *
  page239_i314
#CELL
  pure_quanta q_res *
  page239_i315
#CELL
  pure_quanta q_res *
  page239_i316
#ISCELL
  standard offpage *
  page239_i317
#ISCELL
  standard offpage *
  page239_i318
#ISCELL
  standard offpage *
  page239_i319
#ISCELL
  standard offpage *
  page239_i320
#CELL
  pure_quanta q_res *
  page239_i321
#CELL
  pure_quanta q_res *
  page239_i322
#CELL
  pure_quanta q_res *
  page239_i323
#CELL
  pure_quanta q_res *
  page239_i324
#ISCELL
  standard offpage *
  page239_i325
#ISCELL
  standard offpage *
  page239_i326
#ISCELL
  standard offpage *
  page239_i327
#ISCELL
  standard offpage *
  page239_i328
#ISCELL
  standard offpage *
  page239_i329
#CELL
  pure_quanta q_res *
  page239_i330
#ISCELL
  standard offpage *
  page239_i331
#ISCELL
  standard offpage *
  page239_i332
#CELL
  pure_quanta q_cap *
  page239_i333
#ISCELL
  logical_power universal_gnd *
  page239_i334
#ISCELL
  logical_power universal_gnd *
  page239_i335
#CELL
  pure_quanta q_cap *
  page239_i336
#CELL
  pure_quanta q_res *
  page239_i337
#CELL
  pure_quanta q_res *
  page239_i338
#CELL
  pure_quanta q_res *
  page239_i339
#ISCELL
  standard offpage *
  page239_i340
#ISCELL
  standard offpage *
  page239_i341
#ISCELL
  standard offpage *
  page239_i342
#ISCELL
  standard offpage *
  page239_i343
#ISCELL
  standard offpage *
  page239_i344
#CELL
  pure_quanta q_res *
  page239_i346
#ISCELL
  logical_power universal_gnd *
  page239_i347
#CELL
  pure_quanta q_res *
  page239_i348
#CELL
  pure_quanta max11617eeet *
  page239_i57
#CELL
  pure_quanta q_cap *
  page239_i58
#ISCELL
  logical_power universal_gnd *
  page239_i60
#CELL
  pure_quanta q_cap *
  page239_i61
#CELL
  pure_quanta q_inductor *
  page239_i62
#ISCELL
  logical_power universal_power *
  page239_i63
#ISCELL
  logical_power universal_gnd *
  page239_i64
#CELL
  pure_quanta q_cap *
  page239_i68
#ISCELL
  logical_power universal_gnd *
  page239_i69
#CELL
  pure_quanta q_cap *
  page239_i70
#ISCELL
  logical_power universal_gnd *
  page239_i71
#CELL
  pure_quanta q_res *
  page239_i72
